#ISCELL
  mstr_misc dns *
  *
#ISCELL
  pure_quanta quanta_title_block_c *
  *
#ISCELL
  pure_quanta_power cad_note *
  *
#CELL
  pure_quanta sn74auc2g66dctr *
  page151_i1
#CELL
  pure_quanta q_res *
  page151_i10
#CELL
  pure_quanta q_res *
  page151_i11
#ISCELL
  pure_quanta_power universal_power *
  page151_i12
#ISCELL
  pure_quanta_power gnd *
  page151_i13
#ISCELL
  pure_quanta_power gnd *
  page151_i14
#CELL
  pure_quanta q_cap *
  page151_i15
#ISCELL
  pure_quanta_power universal_power *
  page151_i16
#CELL
  pure_quanta sn74auc2g66dctr *
  page151_i17
#ISCELL
  standard offpage *
  page151_i18
#ISCELL
  pure_quanta_power gnd *
  page151_i19
#CELL
  pure_quanta q_res *
  page151_i2
#ISCELL
  pure_quanta_power universal_power *
  page151_i20
#ISCELL
  pure_quanta_power gnd *
  page151_i21
#CELL
  pure_quanta q_cap *
  page151_i22
#CELL
  pure_quanta sn74auc2g66dctr *
  page151_i23
#CELL
  pure_quanta q_res *
  page151_i25
#ISCELL
  pure_quanta_power universal_power *
  page151_i26
#CELL
  pure_quanta q_res *
  page151_i27
#ISCELL
  pure_quanta_power universal_power *
  page151_i28
#ISCELL
  pure_quanta_power gnd *
  page151_i29
#ISCELL
  pure_quanta_power gnd *
  page151_i3
#ISCELL
  standard offpage *
  page151_i30
#CELL
  pure_quanta sn74auc2g66dctr *
  page151_i31
#ISCELL
  standard offpage *
  page151_i32
#ISCELL
  standard offpage *
  page151_i33
#CELL
  pure_quanta q_res *
  page151_i34
#ISCELL
  pure_quanta_power universal_power *
  page151_i35
#CELL
  pure_quanta q_cap *
  page151_i36
#ISCELL
  pure_quanta_power gnd *
  page151_i37
#ISCELL
  pure_quanta_power gnd *
  page151_i38
#ISCELL
  pure_quanta_power gnd *
  page151_i39
#CELL
  pure_quanta q_cap *
  page151_i4
#ISCELL
  pure_quanta_power gnd *
  page151_i40
#ISCELL
  standard offpage *
  page151_i41
#CELL
  pure_quanta q_cap *
  page151_i42
#ISCELL
  pure_quanta_power gnd *
  page151_i43
#ISCELL
  pure_quanta_power universal_power *
  page151_i44
#CELL
  pure_quanta mosfet_n *
  page151_i45
#CELL
  pure_quanta mosfet_n *
  page151_i46
#ISCELL
  standard offpage *
  page151_i47
#CELL
  pure_quanta q_res *
  page151_i48
#CELL
  pure_quanta q_res *
  page151_i49
#ISCELL
  standard offpage *
  page151_i5
#CELL
  pure_quanta q_res *
  page151_i50
#ISCELL
  standard offpage *
  page151_i6
#ISCELL
  pure_quanta_power universal_power *
  page151_i9
